# S9S_MB_2U (Grand Teton) — schematic netlist excerpt (pin names and nets, part order shuffled) for the footprints in the layout excerpt that follows; sources: Cadence DE-HDL packaged netlist, KiCad conversion of 03242023_DA0F0TMBIJ0_F0T_Motherboard_J_brd_V01_OCP.brd

PC392  Q_CAP  10UF 6.3V 20% X6S  pkg C0402  page 296 : A = PVCCD_HV_CPU1_VREF ; B = GND
PC2173  Q_CAP  10UF 16V 10% EMPTY  pkg C0805  page 163 : A = P3V3_OCP_V3_2_R ; B = GND
R1138  Q_RES  10K 1% CHIP  pkg 0402LF  page 155 : A = P3V3_AUX ; B = CLK_50M_EN

(kicad_pcb
	(version 20260206)
	(generator "pcbnew")
	(generator_version "10.0")
	(general
		(thickness 1.6)
		(legacy_teardrops no)
	)
	(paper "A4")
	(title_block
		(title "03242023_DA0F0TMBIJ0_F0T_Motherboard_J_brd_V01_OCP.brd")
		(comment 1 "Grand Teton / footprints 2805-2807 of 6105")
	)
	(layers
		(0 "F.Cu" signal "TOP")
		(4 "In1.Cu" signal "GND")
		(6 "In2.Cu" signal "IN1")
		(8 "In3.Cu" signal "GND1")
		(10 "In4.Cu" signal "IN2")
		(12 "In5.Cu" signal "GND2")
		(14 "In6.Cu" signal "IN3")
		(16 "In7.Cu" signal "GND3")
		(18 "In8.Cu" signal "VCC")
		(20 "In9.Cu" signal "VCC1")
		(22 "In10.Cu" signal "GND4")
		(24 "In11.Cu" signal "IN4")
		(26 "In12.Cu" signal "GND5")
		(28 "In13.Cu" signal "IN5")
		(30 "In14.Cu" signal "GND6")
		(32 "In15.Cu" signal "IN6")
		(34 "In16.Cu" signal "GND7")
		(2 "B.Cu" signal "BOTTOM")
		(9 "F.Adhes" user "F.Adhesive")
		(11 "B.Adhes" user "B.Adhesive")
		(13 "F.Paste" user "Package Geometry/Pastemask Top")
		(15 "B.Paste" user "Package Geometry/Pastemask Bottom")
		(5 "F.SilkS" user "Ref Des/Silkscreen Top")
		(7 "B.SilkS" user "Ref Des/Silkscreen Bottom")
		(1 "F.Mask" user "Board Geometry/Soldermask Top")
		(3 "B.Mask" user "Board Geometry/Soldermask Bottom")
		(17 "Dwgs.User" user "User.Drawings")
		(19 "Cmts.User" user "User.Comments")
		(21 "Eco1.User" user "User.Eco1")
		(23 "Eco2.User" user "User.Eco2")
		(25 "Edge.Cuts" user "Board Geometry/Outline")
		(27 "Margin" user)
		(31 "F.CrtYd" user "Package Geometry/Place Bound Top")
		(29 "B.CrtYd" user "Package Geometry/Place Bound Bottom")
		(35 "F.Fab" user "Ref Des/Assembly Top")
		(33 "B.Fab" user "Ref Des/Assembly Bottom")
	)
	(footprint ""
		(layer "F.Cu")
		(at 29.977334 -169.000678 90)
		(property "Reference" "PC392"
			(at 0 0 90)
			(layer "F.SilkS")
			(hide yes)
			(effects
				(font
					(size 1.27 1.27)
				)
			)
		)
		(property "Value" ""
			(at 0 0 90)
			(layer "F.Fab")
			(effects
				(font
					(size 1.27 1.27)
				)
			)
		)
		(duplicate_pad_numbers_are_jumpers no)
		(fp_line
			(start 0.7874 -0.4064)
			(end 0.7874 0.4064)
			(stroke
				(width 0.1524)
				(type default)
			)
			(layer "F.SilkS")
		)
		(fp_line
			(start -0.7874 -0.4064)
			(end 0.7874 -0.4064)
			(stroke
				(width 0.1524)
				(type default)
			)
			(layer "F.SilkS")
		)
		(fp_line
			(start 0.7874 0.4064)
			(end -0.7874 0.4064)
			(stroke
				(width 0.1524)
				(type default)
			)
			(layer "F.SilkS")
		)
		(fp_line
			(start -0.7874 0.4064)
			(end -0.7874 -0.4064)
			(stroke
				(width 0.1524)
				(type default)
			)
			(layer "F.SilkS")
		)
		(fp_line
			(start -0.12065 -0.305054)
			(end -0.12065 -0.2794)
			(stroke
				(width 0.1)
				(type default)
			)
			(layer "F.Fab")
		)
		(fp_line
			(start -0.67945 -0.305054)
			(end -0.12065 -0.305054)
			(stroke
				(width 0.1)
				(type default)
			)
			(layer "F.Fab")
		)
		(fp_line
			(start 0.67945 -0.3048)
			(end 0.67945 0.3048)
			(stroke
				(width 0.1)
				(type default)
			)
			(layer "F.Fab")
		)
		(fp_line
			(start 0.12065 -0.3048)
			(end 0.67945 -0.3048)
			(stroke
				(width 0.1)
				(type default)
			)
			(layer "F.Fab")
		)
		(fp_line
			(start 0.12065 -0.2794)
			(end 0.12065 -0.3048)
			(stroke
				(width 0.1)
				(type default)
			)
			(layer "F.Fab")
		)
		(fp_line
			(start -0.12065 -0.2794)
			(end 0.12065 -0.2794)
			(stroke
				(width 0.1)
				(type default)
			)
			(layer "F.Fab")
		)
		(fp_line
			(start 0.120396 0.2794)
			(end -0.12065 0.2794)
			(stroke
				(width 0.1)
				(type default)
			)
			(layer "F.Fab")
		)
		(fp_line
			(start -0.12065 0.2794)
			(end -0.12065 0.3048)
			(stroke
				(width 0.1)
				(type default)
			)
			(layer "F.Fab")
		)
		(fp_line
			(start 0.67945 0.3048)
			(end 0.120396 0.3048)
			(stroke
				(width 0.1)
				(type default)
			)
			(layer "F.Fab")
		)
		(fp_line
			(start 0.120396 0.3048)
			(end 0.120396 0.2794)
			(stroke
				(width 0.1)
				(type default)
			)
			(layer "F.Fab")
		)
		(fp_line
			(start -0.12065 0.3048)
			(end -0.67945 0.3048)
			(stroke
				(width 0.1)
				(type default)
			)
			(layer "F.Fab")
		)
		(fp_line
			(start -0.67945 0.3048)
			(end -0.67945 -0.305054)
			(stroke
				(width 0.1)
				(type default)
			)
			(layer "F.Fab")
		)
		(pad "1" smd circle
			(at -0.40005 0 90)
			(size 0 0)
			(layers "F.Cu" "F.Mask" "F.Paste")
			(net "PVCCD_HV_CPU1_VREF")
		)
		(pad "2" smd circle
			(at 0.40005 0 90)
			(size 0 0)
			(layers "F.Cu" "F.Mask" "F.Paste")
			(net "GND")
		)
	)
	(footprint ""
		(layer "F.Cu")
		(at 214.61349 -23.304754 90)
		(property "Reference" "R1138"
			(at 0 0 90)
			(layer "F.SilkS")
			(hide yes)
			(effects
				(font
					(size 1.27 1.27)
				)
			)
		)
		(property "Value" ""
			(at 0 0 90)
			(layer "F.Fab")
			(effects
				(font
					(size 1.27 1.27)
				)
			)
		)
		(duplicate_pad_numbers_are_jumpers no)
		(fp_line
			(start 0.7874 -0.4064)
			(end 0.7874 0.4064)
			(stroke
				(width 0.1524)
				(type default)
			)
			(layer "F.SilkS")
		)
		(fp_line
			(start -0.7874 -0.4064)
			(end 0.7874 -0.4064)
			(stroke
				(width 0.1524)
				(type default)
			)
			(layer "F.SilkS")
		)
		(fp_line
			(start 0.7874 0.4064)
			(end -0.7874 0.4064)
			(stroke
				(width 0.1524)
				(type default)
			)
			(layer "F.SilkS")
		)
		(fp_line
			(start -0.7874 0.4064)
			(end -0.7874 -0.4064)
			(stroke
				(width 0.1524)
				(type default)
			)
			(layer "F.SilkS")
		)
		(fp_line
			(start -0.12065 -0.305054)
			(end -0.12065 -0.2794)
			(stroke
				(width 0.1)
				(type default)
			)
			(layer "F.Fab")
		)
		(fp_line
			(start -0.67945 -0.305054)
			(end -0.12065 -0.305054)
			(stroke
				(width 0.1)
				(type default)
			)
			(layer "F.Fab")
		)
		(fp_line
			(start 0.67945 -0.3048)
			(end 0.67945 0.3048)
			(stroke
				(width 0.1)
				(type default)
			)
			(layer "F.Fab")
		)
		(fp_line
			(start 0.12065 -0.3048)
			(end 0.67945 -0.3048)
			(stroke
				(width 0.1)
				(type default)
			)
			(layer "F.Fab")
		)
		(fp_line
			(start 0.12065 -0.2794)
			(end 0.12065 -0.3048)
			(stroke
				(width 0.1)
				(type default)
			)
			(layer "F.Fab")
		)
		(fp_line
			(start -0.12065 -0.2794)
			(end 0.12065 -0.2794)
			(stroke
				(width 0.1)
				(type default)
			)
			(layer "F.Fab")
		)
		(fp_line
			(start 0.120396 0.2794)
			(end -0.12065 0.2794)
			(stroke
				(width 0.1)
				(type default)
			)
			(layer "F.Fab")
		)
		(fp_line
			(start -0.12065 0.2794)
			(end -0.12065 0.3048)
			(stroke
				(width 0.1)
				(type default)
			)
			(layer "F.Fab")
		)
		(fp_line
			(start 0.67945 0.3048)
			(end 0.120396 0.3048)
			(stroke
				(width 0.1)
				(type default)
			)
			(layer "F.Fab")
		)
		(fp_line
			(start 0.120396 0.3048)
			(end 0.120396 0.2794)
			(stroke
				(width 0.1)
				(type default)
			)
			(layer "F.Fab")
		)
		(fp_line
			(start -0.12065 0.3048)
			(end -0.67945 0.3048)
			(stroke
				(width 0.1)
				(type default)
			)
			(layer "F.Fab")
		)
		(fp_line
			(start -0.67945 0.3048)
			(end -0.67945 -0.305054)
			(stroke
				(width 0.1)
				(type default)
			)
			(layer "F.Fab")
		)
		(pad "1" smd circle
			(at -0.40005 0 90)
			(size 0 0)
			(layers "F.Cu" "F.Mask" "F.Paste")
			(net "P3V3_AUX")
		)
		(pad "2" smd circle
			(at 0.40005 0 90)
			(size 0 0)
			(layers "F.Cu" "F.Mask" "F.Paste")
			(net "CLK_50M_EN")
		)
	)
	(footprint ""
		(layer "F.Cu")
		(at 71.79056 -56.159908 -90)
		(property "Reference" "PC2173"
			(at 0 0 270)
			(layer "F.SilkS")
			(hide yes)
			(effects
				(font
					(size 1.27 1.27)
				)
			)
		)
		(property "Value" ""
			(at 0 0 270)
			(layer "F.Fab")
			(effects
				(font
					(size 1.27 1.27)
				)
			)
		)
		(duplicate_pad_numbers_are_jumpers no)
		(fp_line
			(start -1.524 0.762)
			(end -1.524 -0.762)
			(stroke
				(width 0.1524)
				(type default)
			)
			(layer "F.SilkS")
		)
		(fp_line
			(start 1.524 0.762)
			(end -1.524 0.762)
			(stroke
				(width 0.1524)
				(type default)
			)
			(layer "F.SilkS")
		)
		(fp_line
			(start -1.524 -0.762)
			(end 1.524 -0.762)
			(stroke
				(width 0.1524)
				(type default)
			)
			(layer "F.SilkS")
		)
		(fp_line
			(start 1.524 -0.762)
			(end 1.524 0.762)
			(stroke
				(width 0.1524)
				(type default)
			)
			(layer "F.SilkS")
		)
		(fp_line
			(start -1.1049 0.724916)
			(end 1.1049 0.724916)
			(stroke
				(width 0.1)
				(type default)
			)
			(layer "F.Fab")
		)
		(fp_line
			(start 1.1049 0.724916)
			(end 1.1049 -0.724916)
			(stroke
				(width 0.1)
				(type default)
			)
			(layer "F.Fab")
		)
		(fp_line
			(start -1.1049 -0.724916)
			(end -1.1049 0.724916)
			(stroke
				(width 0.1)
				(type default)
			)
			(layer "F.Fab")
		)
		(fp_line
			(start 1.1049 -0.724916)
			(end -1.1049 -0.724916)
			(stroke
				(width 0.1)
				(type default)
			)
			(layer "F.Fab")
		)
		(pad "1" smd rect
			(at -0.889 0 90)
			(size 1.016 1.27)
			(layers "F.Cu" "F.Mask" "F.Paste")
			(net "P3V3_OCP_V3_2_R")
		)
		(pad "2" smd rect
			(at 0.889 0 90)
			(size 1.016 1.27)
			(layers "F.Cu" "F.Mask" "F.Paste")
			(net "GND")
		)
	)
)
